# T6G (Grand Teton) — schematic netlist excerpt (pin names and nets, part order shuffled) for the footprints in the layout excerpt that follows; sources: Cadence DE-HDL packaged netlist, KiCad conversion of 04192023_DAF0TMB3IC0_F0TG_MB_C_brd_V02_OCP.brd

PR256  Q_RES  2.2 1% CHIP  pkg 0402LF  page 218 : A = PVDDCR_CPU1_P1_PVCC ; B = PVDDCR_CPU1_P1_VCC1
R1424  Q_RES  2.2K 5% CHIP  pkg 0402LF  page 55 : A = PVDD18_S5_P1 ; B = INT_CPU1_HP_UBM_N

(kicad_pcb
	(version 20260206)
	(generator "pcbnew")
	(generator_version "10.0")
	(general
		(thickness 1.6)
		(legacy_teardrops no)
	)
	(paper "A4")
	(title_block
		(title "04192023_DAF0TMB3IC0_F0TG_MB_C_brd_V02_OCP.brd")
		(comment 1 "Grand Teton / footprints 8085-8086 of 8354")
	)
	(layers
		(0 "F.Cu" signal "TOP")
		(4 "In1.Cu" signal "GND")
		(6 "In2.Cu" signal "IN1")
		(8 "In3.Cu" signal "GND1")
		(10 "In4.Cu" signal "IN2")
		(12 "In5.Cu" signal "GND2")
		(14 "In6.Cu" signal "IN3")
		(16 "In7.Cu" signal "GND3")
		(18 "In8.Cu" signal "VCC")
		(20 "In9.Cu" signal "VCC1")
		(22 "In10.Cu" signal "GND4")
		(24 "In11.Cu" signal "IN4")
		(26 "In12.Cu" signal "GND5")
		(28 "In13.Cu" signal "IN5")
		(30 "In14.Cu" signal "GND6")
		(32 "In15.Cu" signal "IN6")
		(34 "In16.Cu" signal "GND7")
		(2 "B.Cu" signal "BOTTOM")
		(9 "F.Adhes" user "F.Adhesive")
		(11 "B.Adhes" user "B.Adhesive")
		(13 "F.Paste" user "Package Geometry/Pastemask Top")
		(15 "B.Paste" user "Package Geometry/Pastemask Bottom")
		(5 "F.SilkS" user "Ref Des/Silkscreen Top")
		(7 "B.SilkS" user "Ref Des/Silkscreen Bottom")
		(1 "F.Mask" user "Board Geometry/Soldermask Top")
		(3 "B.Mask" user "Board Geometry/Soldermask Bottom")
		(17 "Dwgs.User" user "User.Drawings")
		(19 "Cmts.User" user "User.Comments")
		(21 "Eco1.User" user "User.Eco1")
		(23 "Eco2.User" user "User.Eco2")
		(25 "Edge.Cuts" user "Board Geometry/Outline")
		(27 "Margin" user)
		(31 "F.CrtYd" user "Package Geometry/Place Bound Top")
		(29 "B.CrtYd" user "Package Geometry/Place Bound Bottom")
		(35 "F.Fab" user "Ref Des/Assembly Top")
		(33 "B.Fab" user "Ref Des/Assembly Bottom")
	)
	(footprint ""
		(layer "B.Cu")
		(at 96.842834 -306.701952 180)
		(property "Reference" "R1424"
			(at 0 0 0)
			(layer "B.SilkS")
			(hide yes)
			(effects
				(font
					(size 1.27 1.27)
				)
				(justify mirror)
			)
		)
		(property "Value" ""
			(at 0 0 0)
			(layer "B.Fab")
			(effects
				(font
					(size 1.27 1.27)
				)
				(justify mirror)
			)
		)
		(duplicate_pad_numbers_are_jumpers no)
		(fp_line
			(start 0.7874 0.4064)
			(end 0.7874 -0.4064)
			(stroke
				(width 0.1524)
				(type default)
			)
			(layer "B.SilkS")
		)
		(fp_line
			(start 0.7874 -0.4064)
			(end -0.7874 -0.4064)
			(stroke
				(width 0.1524)
				(type default)
			)
			(layer "B.SilkS")
		)
		(fp_line
			(start -0.7874 0.4064)
			(end 0.7874 0.4064)
			(stroke
				(width 0.1524)
				(type default)
			)
			(layer "B.SilkS")
		)
		(fp_line
			(start -0.7874 -0.4064)
			(end -0.7874 0.4064)
			(stroke
				(width 0.1524)
				(type default)
			)
			(layer "B.SilkS")
		)
		(fp_line
			(start 0.67945 0.3048)
			(end 0.67945 -0.305054)
			(stroke
				(width 0.1)
				(type default)
			)
			(layer "B.Fab")
		)
		(fp_line
			(start 0.67945 -0.305054)
			(end 0.12065 -0.305054)
			(stroke
				(width 0.1)
				(type default)
			)
			(layer "B.Fab")
		)
		(fp_line
			(start 0.12065 0.3048)
			(end 0.67945 0.3048)
			(stroke
				(width 0.1)
				(type default)
			)
			(layer "B.Fab")
		)
		(fp_line
			(start 0.12065 0.2794)
			(end 0.12065 0.3048)
			(stroke
				(width 0.1)
				(type default)
			)
			(layer "B.Fab")
		)
		(fp_line
			(start 0.12065 -0.2794)
			(end -0.12065 -0.2794)
			(stroke
				(width 0.1)
				(type default)
			)
			(layer "B.Fab")
		)
		(fp_line
			(start 0.12065 -0.305054)
			(end 0.12065 -0.2794)
			(stroke
				(width 0.1)
				(type default)
			)
			(layer "B.Fab")
		)
		(fp_line
			(start -0.120396 0.3048)
			(end -0.120396 0.2794)
			(stroke
				(width 0.1)
				(type default)
			)
			(layer "B.Fab")
		)
		(fp_line
			(start -0.120396 0.2794)
			(end 0.12065 0.2794)
			(stroke
				(width 0.1)
				(type default)
			)
			(layer "B.Fab")
		)
		(fp_line
			(start -0.12065 -0.2794)
			(end -0.12065 -0.3048)
			(stroke
				(width 0.1)
				(type default)
			)
			(layer "B.Fab")
		)
		(fp_line
			(start -0.12065 -0.3048)
			(end -0.67945 -0.3048)
			(stroke
				(width 0.1)
				(type default)
			)
			(layer "B.Fab")
		)
		(fp_line
			(start -0.67945 0.3048)
			(end -0.120396 0.3048)
			(stroke
				(width 0.1)
				(type default)
			)
			(layer "B.Fab")
		)
		(fp_line
			(start -0.67945 -0.3048)
			(end -0.67945 0.3048)
			(stroke
				(width 0.1)
				(type default)
			)
			(layer "B.Fab")
		)
		(pad "1" smd circle
			(at 0.40005 0)
			(size 0 0)
			(layers "B.Cu" "B.Mask" "B.Paste")
			(net "PVDD18_S5_P1")
		)
		(pad "2" smd circle
			(at -0.40005 0)
			(size 0 0)
			(layers "B.Cu" "B.Mask" "B.Paste")
			(net "INT_CPU1_HP_UBM_N")
		)
	)
	(footprint ""
		(layer "B.Cu")
		(at 84.811362 -336.037682 -90)
		(property "Reference" "PR256"
			(at 0 0 90)
			(layer "B.SilkS")
			(hide yes)
			(effects
				(font
					(size 1.27 1.27)
				)
				(justify mirror)
			)
		)
		(property "Value" ""
			(at 0 0 90)
			(layer "B.Fab")
			(effects
				(font
					(size 1.27 1.27)
				)
				(justify mirror)
			)
		)
		(duplicate_pad_numbers_are_jumpers no)
		(fp_line
			(start -0.7874 0.4064)
			(end 0.7874 0.4064)
			(stroke
				(width 0.1524)
				(type default)
			)
			(layer "B.SilkS")
		)
		(fp_line
			(start 0.7874 0.4064)
			(end 0.7874 -0.4064)
			(stroke
				(width 0.1524)
				(type default)
			)
			(layer "B.SilkS")
		)
		(fp_line
			(start -0.7874 -0.4064)
			(end -0.7874 0.4064)
			(stroke
				(width 0.1524)
				(type default)
			)
			(layer "B.SilkS")
		)
		(fp_line
			(start 0.7874 -0.4064)
			(end -0.7874 -0.4064)
			(stroke
				(width 0.1524)
				(type default)
			)
			(layer "B.SilkS")
		)
		(fp_line
			(start -0.67945 0.3048)
			(end -0.120396 0.3048)
			(stroke
				(width 0.1)
				(type default)
			)
			(layer "B.Fab")
		)
		(fp_line
			(start -0.120396 0.3048)
			(end -0.120396 0.2794)
			(stroke
				(width 0.1)
				(type default)
			)
			(layer "B.Fab")
		)
		(fp_line
			(start 0.12065 0.3048)
			(end 0.67945 0.3048)
			(stroke
				(width 0.1)
				(type default)
			)
			(layer "B.Fab")
		)
		(fp_line
			(start 0.67945 0.3048)
			(end 0.67945 -0.305054)
			(stroke
				(width 0.1)
				(type default)
			)
			(layer "B.Fab")
		)
		(fp_line
			(start -0.120396 0.2794)
			(end 0.12065 0.2794)
			(stroke
				(width 0.1)
				(type default)
			)
			(layer "B.Fab")
		)
		(fp_line
			(start 0.12065 0.2794)
			(end 0.12065 0.3048)
			(stroke
				(width 0.1)
				(type default)
			)
			(layer "B.Fab")
		)
		(fp_line
			(start -0.12065 -0.2794)
			(end -0.12065 -0.3048)
			(stroke
				(width 0.1)
				(type default)
			)
			(layer "B.Fab")
		)
		(fp_line
			(start 0.12065 -0.2794)
			(end -0.12065 -0.2794)
			(stroke
				(width 0.1)
				(type default)
			)
			(layer "B.Fab")
		)
		(fp_line
			(start -0.67945 -0.3048)
			(end -0.67945 0.3048)
			(stroke
				(width 0.1)
				(type default)
			)
			(layer "B.Fab")
		)
		(fp_line
			(start -0.12065 -0.3048)
			(end -0.67945 -0.3048)
			(stroke
				(width 0.1)
				(type default)
			)
			(layer "B.Fab")
		)
		(fp_line
			(start 0.12065 -0.305054)
			(end 0.12065 -0.2794)
			(stroke
				(width 0.1)
				(type default)
			)
			(layer "B.Fab")
		)
		(fp_line
			(start 0.67945 -0.305054)
			(end 0.12065 -0.305054)
			(stroke
				(width 0.1)
				(type default)
			)
			(layer "B.Fab")
		)
		(pad "1" smd circle
			(at 0.40005 0 90)
			(size 0 0)
			(layers "B.Cu" "B.Mask" "B.Paste")
			(net "PVDDCR_CPU1_P1_PVCC")
		)
		(pad "2" smd circle
			(at -0.40005 0 90)
			(size 0 0)
			(layers "B.Cu" "B.Mask" "B.Paste")
			(net "PVDDCR_CPU1_P1_VCC1")
		)
	)
)
